# S9S_MB_2U (Grand Teton) — schematic netlist excerpt (pin names and nets, part order shuffled) for the footprints in the layout excerpt that follows; sources: Cadence DE-HDL packaged netlist, KiCad conversion of 03242023_DA0F0TMBIJ0_F0T_Motherboard_J_brd_V01_OCP.brd

PR1340  Q_RES  38.3K 0.1% CHIP  pkg 0402LF  page 299 : A = PVPP_HBM_CPU1_FB ; B = SH_PVPP_HBM_CPU1_P
PC1262  Q_CAP  1UF 16V 10% X6S  pkg C0402  page 299 : A = SW_P12V_PVCCIN_CPU1_FLT ; B = GND
C955  Q_CAP_DIFFBUS  DIFF BUS_0.22UF 6.3V 20% X6S  pkg C0201  page 173 : \1\ = P5E_CPU0_PE2_TX_C_DP<5> ; \2\ = P5E_CPU0_PE2_TX_DP<5>

(kicad_pcb
	(version 20260206)
	(generator "pcbnew")
	(generator_version "10.0")
	(general
		(thickness 1.6)
		(legacy_teardrops no)
	)
	(paper "A4")
	(title_block
		(title "03242023_DA0F0TMBIJ0_F0T_Motherboard_J_brd_V01_OCP.brd")
		(comment 1 "Grand Teton / footprints 2303-2305 of 6105")
	)
	(layers
		(0 "F.Cu" signal "TOP")
		(4 "In1.Cu" signal "GND")
		(6 "In2.Cu" signal "IN1")
		(8 "In3.Cu" signal "GND1")
		(10 "In4.Cu" signal "IN2")
		(12 "In5.Cu" signal "GND2")
		(14 "In6.Cu" signal "IN3")
		(16 "In7.Cu" signal "GND3")
		(18 "In8.Cu" signal "VCC")
		(20 "In9.Cu" signal "VCC1")
		(22 "In10.Cu" signal "GND4")
		(24 "In11.Cu" signal "IN4")
		(26 "In12.Cu" signal "GND5")
		(28 "In13.Cu" signal "IN5")
		(30 "In14.Cu" signal "GND6")
		(32 "In15.Cu" signal "IN6")
		(34 "In16.Cu" signal "GND7")
		(2 "B.Cu" signal "BOTTOM")
		(9 "F.Adhes" user "F.Adhesive")
		(11 "B.Adhes" user "B.Adhesive")
		(13 "F.Paste" user "Package Geometry/Pastemask Top")
		(15 "B.Paste" user "Package Geometry/Pastemask Bottom")
		(5 "F.SilkS" user "Ref Des/Silkscreen Top")
		(7 "B.SilkS" user "Ref Des/Silkscreen Bottom")
		(1 "F.Mask" user "Board Geometry/Soldermask Top")
		(3 "B.Mask" user "Board Geometry/Soldermask Bottom")
		(17 "Dwgs.User" user "User.Drawings")
		(19 "Cmts.User" user "User.Comments")
		(21 "Eco1.User" user "User.Eco1")
		(23 "Eco2.User" user "User.Eco2")
		(25 "Edge.Cuts" user "Board Geometry/Outline")
		(27 "Margin" user)
		(31 "F.CrtYd" user "Package Geometry/Place Bound Top")
		(29 "B.CrtYd" user "Package Geometry/Place Bound Bottom")
		(35 "F.Fab" user "Ref Des/Assembly Top")
		(33 "B.Fab" user "Ref Des/Assembly Bottom")
	)
	(footprint ""
		(layer "F.Cu")
		(at 120.066054 -357.11638 90)
		(property "Reference" "PR1340"
			(at 0 0 90)
			(layer "F.SilkS")
			(hide yes)
			(effects
				(font
					(size 1.27 1.27)
				)
			)
		)
		(property "Value" ""
			(at 0 0 90)
			(layer "F.Fab")
			(effects
				(font
					(size 1.27 1.27)
				)
			)
		)
		(duplicate_pad_numbers_are_jumpers no)
		(fp_line
			(start 0.7874 -0.4064)
			(end 0.7874 0.4064)
			(stroke
				(width 0.1524)
				(type default)
			)
			(layer "F.SilkS")
		)
		(fp_line
			(start -0.7874 -0.4064)
			(end 0.7874 -0.4064)
			(stroke
				(width 0.1524)
				(type default)
			)
			(layer "F.SilkS")
		)
		(fp_line
			(start 0.7874 0.4064)
			(end -0.7874 0.4064)
			(stroke
				(width 0.1524)
				(type default)
			)
			(layer "F.SilkS")
		)
		(fp_line
			(start -0.7874 0.4064)
			(end -0.7874 -0.4064)
			(stroke
				(width 0.1524)
				(type default)
			)
			(layer "F.SilkS")
		)
		(fp_line
			(start -0.12065 -0.305054)
			(end -0.12065 -0.2794)
			(stroke
				(width 0.1)
				(type default)
			)
			(layer "F.Fab")
		)
		(fp_line
			(start -0.67945 -0.305054)
			(end -0.12065 -0.305054)
			(stroke
				(width 0.1)
				(type default)
			)
			(layer "F.Fab")
		)
		(fp_line
			(start 0.67945 -0.3048)
			(end 0.67945 0.3048)
			(stroke
				(width 0.1)
				(type default)
			)
			(layer "F.Fab")
		)
		(fp_line
			(start 0.12065 -0.3048)
			(end 0.67945 -0.3048)
			(stroke
				(width 0.1)
				(type default)
			)
			(layer "F.Fab")
		)
		(fp_line
			(start 0.12065 -0.2794)
			(end 0.12065 -0.3048)
			(stroke
				(width 0.1)
				(type default)
			)
			(layer "F.Fab")
		)
		(fp_line
			(start -0.12065 -0.2794)
			(end 0.12065 -0.2794)
			(stroke
				(width 0.1)
				(type default)
			)
			(layer "F.Fab")
		)
		(fp_line
			(start 0.120396 0.2794)
			(end -0.12065 0.2794)
			(stroke
				(width 0.1)
				(type default)
			)
			(layer "F.Fab")
		)
		(fp_line
			(start -0.12065 0.2794)
			(end -0.12065 0.3048)
			(stroke
				(width 0.1)
				(type default)
			)
			(layer "F.Fab")
		)
		(fp_line
			(start 0.67945 0.3048)
			(end 0.120396 0.3048)
			(stroke
				(width 0.1)
				(type default)
			)
			(layer "F.Fab")
		)
		(fp_line
			(start 0.120396 0.3048)
			(end 0.120396 0.2794)
			(stroke
				(width 0.1)
				(type default)
			)
			(layer "F.Fab")
		)
		(fp_line
			(start -0.12065 0.3048)
			(end -0.67945 0.3048)
			(stroke
				(width 0.1)
				(type default)
			)
			(layer "F.Fab")
		)
		(fp_line
			(start -0.67945 0.3048)
			(end -0.67945 -0.305054)
			(stroke
				(width 0.1)
				(type default)
			)
			(layer "F.Fab")
		)
		(pad "1" smd circle
			(at -0.40005 0 90)
			(size 0 0)
			(layers "F.Cu" "F.Mask" "F.Paste")
			(net "PVPP_HBM_CPU1_FB")
		)
		(pad "2" smd circle
			(at 0.40005 0 90)
			(size 0 0)
			(layers "F.Cu" "F.Mask" "F.Paste")
			(net "SH_PVPP_HBM_CPU1_P")
		)
	)
	(footprint ""
		(layer "F.Cu")
		(at 402.02993 -402.371052 -90)
		(property "Reference" "C955"
			(at 0 0 270)
			(layer "F.SilkS")
			(hide yes)
			(effects
				(font
					(size 1.27 1.27)
				)
			)
		)
		(property "Value" ""
			(at 0 0 270)
			(layer "F.Fab")
			(effects
				(font
					(size 1.27 1.27)
				)
			)
		)
		(duplicate_pad_numbers_are_jumpers no)
		(fp_line
			(start -0.299974 0.150114)
			(end -0.299974 -0.150114)
			(stroke
				(width 0.1)
				(type default)
			)
			(layer "F.Fab")
		)
		(fp_line
			(start 0.299974 0.150114)
			(end -0.299974 0.150114)
			(stroke
				(width 0.1)
				(type default)
			)
			(layer "F.Fab")
		)
		(fp_line
			(start -0.299974 -0.150114)
			(end 0.299974 -0.150114)
			(stroke
				(width 0.1)
				(type default)
			)
			(layer "F.Fab")
		)
		(fp_line
			(start 0.299974 -0.150114)
			(end 0.299974 0.150114)
			(stroke
				(width 0.1)
				(type default)
			)
			(layer "F.Fab")
		)
		(pad "1" smd rect
			(at -0.2667 0 270)
			(size 0.3048 0.381)
			(layers "F.Cu" "F.Mask" "F.Paste")
			(net "P5E_CPU0_PE2_TX_C_DP<5>")
		)
		(pad "2" smd rect
			(at 0.2667 0 270)
			(size 0.3048 0.381)
			(layers "F.Cu" "F.Mask" "F.Paste")
			(net "P5E_CPU0_PE2_TX_DP<5>")
		)
	)
	(footprint ""
		(layer "F.Cu")
		(at 124.931424 -361.704382 180)
		(property "Reference" "PC1262"
			(at 0 0 180)
			(layer "F.SilkS")
			(hide yes)
			(effects
				(font
					(size 1.27 1.27)
				)
			)
		)
		(property "Value" ""
			(at 0 0 180)
			(layer "F.Fab")
			(effects
				(font
					(size 1.27 1.27)
				)
			)
		)
		(duplicate_pad_numbers_are_jumpers no)
		(fp_line
			(start 0.7874 0.4064)
			(end -0.7874 0.4064)
			(stroke
				(width 0.1524)
				(type default)
			)
			(layer "F.SilkS")
		)
		(fp_line
			(start 0.7874 -0.4064)
			(end 0.7874 0.4064)
			(stroke
				(width 0.1524)
				(type default)
			)
			(layer "F.SilkS")
		)
		(fp_line
			(start -0.7874 0.4064)
			(end -0.7874 -0.4064)
			(stroke
				(width 0.1524)
				(type default)
			)
			(layer "F.SilkS")
		)
		(fp_line
			(start -0.7874 -0.4064)
			(end 0.7874 -0.4064)
			(stroke
				(width 0.1524)
				(type default)
			)
			(layer "F.SilkS")
		)
		(fp_line
			(start 0.67945 0.3048)
			(end 0.120396 0.3048)
			(stroke
				(width 0.1)
				(type default)
			)
			(layer "F.Fab")
		)
		(fp_line
			(start 0.67945 -0.3048)
			(end 0.67945 0.3048)
			(stroke
				(width 0.1)
				(type default)
			)
			(layer "F.Fab")
		)
		(fp_line
			(start 0.12065 -0.2794)
			(end 0.12065 -0.3048)
			(stroke
				(width 0.1)
				(type default)
			)
			(layer "F.Fab")
		)
		(fp_line
			(start 0.12065 -0.3048)
			(end 0.67945 -0.3048)
			(stroke
				(width 0.1)
				(type default)
			)
			(layer "F.Fab")
		)
		(fp_line
			(start 0.120396 0.3048)
			(end 0.120396 0.2794)
			(stroke
				(width 0.1)
				(type default)
			)
			(layer "F.Fab")
		)
		(fp_line
			(start 0.120396 0.2794)
			(end -0.12065 0.2794)
			(stroke
				(width 0.1)
				(type default)
			)
			(layer "F.Fab")
		)
		(fp_line
			(start -0.12065 0.3048)
			(end -0.67945 0.3048)
			(stroke
				(width 0.1)
				(type default)
			)
			(layer "F.Fab")
		)
		(fp_line
			(start -0.12065 0.2794)
			(end -0.12065 0.3048)
			(stroke
				(width 0.1)
				(type default)
			)
			(layer "F.Fab")
		)
		(fp_line
			(start -0.12065 -0.2794)
			(end 0.12065 -0.2794)
			(stroke
				(width 0.1)
				(type default)
			)
			(layer "F.Fab")
		)
		(fp_line
			(start -0.12065 -0.305054)
			(end -0.12065 -0.2794)
			(stroke
				(width 0.1)
				(type default)
			)
			(layer "F.Fab")
		)
		(fp_line
			(start -0.67945 0.3048)
			(end -0.67945 -0.305054)
			(stroke
				(width 0.1)
				(type default)
			)
			(layer "F.Fab")
		)
		(fp_line
			(start -0.67945 -0.305054)
			(end -0.12065 -0.305054)
			(stroke
				(width 0.1)
				(type default)
			)
			(layer "F.Fab")
		)
		(pad "1" smd circle
			(at -0.40005 0 180)
			(size 0 0)
			(layers "F.Cu" "F.Mask" "F.Paste")
			(net "SW_P12V_PVCCIN_CPU1_FLT")
		)
		(pad "2" smd circle
			(at 0.40005 0 180)
			(size 0 0)
			(layers "F.Cu" "F.Mask" "F.Paste")
			(net "GND")
		)
	)
)
